FILE_TYPE = CONNECTIVITY;
{Allegro Design Entry HDL 17.2-2016 S081 (4005846) 1/11/2022}
"PAGE_NUMBER" = 255;
0"NC";
1"PVCCIN_CPU0_PVCC\g";
2"PVCCIN_CPU0_PVCC\g";
3"SW_P12V_PVCCIN_CPU0_FLT\g";
4"SW_P12V_PVCCIN_CPU0_FLT\g";
5"PVCCIN_CPU0\g";
6"PVCCIN_CPU0\g";
7"GND\g";
8"GND\g";
9"GND\g";
10"GND\g";
11"GND\g";
12"GND\g";
13"GND\g";
14"GND\g";
15"GND\g";
16"GND\g";
17"GND\g";
18"GND\g";
19"GND\g";
20"GND\g";
21"IND_P0_CPL8";
22"IND_P0_CPL5";
23"SW_PVCCIN_CPU0_BOOT5_R";
24"SW_PVCCIN_CPU0_SW5";
25"SW_PVCCIN_CPU0_BOOTR5";
26"SW_PVCCIN_CPU0_BOOT5";
27"PVCCIN_CPU0_VOS5";
28"IND_P0_CPL1";
29"SW_PVCCIN_CPU0_BOOT6_R";
30"SW_PVCCIN_CPU0_BOOT6";
31"IND_P0_CPL6";
32"SW_PVCCIN_CPU0_BOOTR6";
33"SW_PVCCIN_CPU0_SW6";
34"PVCCIN_CPU0_VOS6";
35"PVCCIN_CPU0_VDD5";
36"PVCCIN_CPU0_VREF"CDS_PHYS_NET_NAME"PVCCIN_CPU0_VREF";
37"PVCCIN_CPU0_IMON5";
38"PVCCIN_CPU0_LSET5";
39"PVCCIN_CPU0_PWM5";
40"PVCCIN_CPU0_ATSEN";
41"PVCCIN_CPU0_VDD6";
42"PVCCIN_CPU0_IMON6";
43"PVCCIN_CPU0_VREF"CDS_PHYS_NET_NAME"PVCCIN_CPU0_VREF";
44"PVCCIN_CPU0_ATSEN";
45"PVCCIN_CPU0_PWM6";
46"PVCCIN_CPU0_LSET6";
%"UNIVERSAL_GND"
"1","(1675,1175)","0","logical_power","I1";
;
CDS_LIB"logical_power"
HDL_POWER"GND";
"A"7;
%"UNIVERSAL_GND"
"1","(2075,2150)","0","logical_power","I10";
;
CDS_LIB"logical_power"
HDL_POWER"GND";
"A"10;
%"Q_CAP"
"2","(2400,1700)","0","pure_quanta","I11";
;
PART_NUMBER"CH4104K1B00"
PACK_TYPE"0402"
VOLTAGE"25V"
MATERIAL"X7R"
TOLERANCE"10%"
VALUE"0.1UF"
LOCATION"PC1342"
CDS_LIB"pure_quanta"
$SEC"1"
CDS_SEC"1";
"A"
$PN"1"8;
"B"
$PN"2"43;
%"ISL99390FRZTR5935"
"1","(3600,1900)","0","pure_quanta","I12";
;
PART_NUMBER"AL099390004"
PART_TYPE"SMLF"
MATERIAL"IC"
VALUE"ISL99390FRZ-TR5935"
LOCATION"PU8_P0_6"
NEEDS_NO_SIZE"TRUE"
CDS_LMAN_SYM_OUTLINE"-300,700,250,-650"
CDS_LIB"pure_quanta"
SEC_TYPE""
SEC"1";
"PGND2"
$PN"7_9-20_24"15;
"GL2"
$PN"41"0;
"GL1"
$PN"6"0;
"DNC"
$PN"31"0;
"EN"
$PN"35"41;
"PGND3"
$PN"40"15;
"VOS"
$PN"1"34;
"VIN2"
$PN"30"3;
"PGND1"
$PN"5"15;
"SW"
$PN"10_19"33;
"LSET"
$PN"37"46;
"IOUT"
$PN"38"42;
"TOUT_FLT"
$PN"36"44;
"PVCC"
$PN"4"1;
"PHASE"
$PN"32"32;
"VIN1"
$PN"25_29"3;
"BOOT"
$PN"33"30;
"AGND"
$PN"2"15;
"VCC"
$PN"3"41;
"REFIN"
$PN"39"43;
"PWM"
$PN"34"45;
%"Q_CAP"
"1","(2075,2400)","0","pure_quanta","I13";
;
PART_NUMBER"CH5222KEB01"
MATERIAL"X6S"
TOLERANCE"10%"
VALUE"2.2UF"
VOLTAGE"10V"
PACK_TYPE"C0402"
LOCATION"PC248"
CDS_LIB"pure_quanta"
LOCATION"PC248"
$SEC"1"
CDS_SEC"1";
"B"
$PN"2"10;
"A"
$PN"1"41;
%"Q_RES"
"2","(2075,2900)","0","pure_quanta","I14";
;
PART_NUMBER"CS-2202FB01"
WATTAGE"1/16W"
MATERIAL"CHIP"
TOLERANCE"1%"
VALUE"2.2"
PACK_TYPE"0402LF"
LOCATION"PR140"
CDS_LIB"pure_quanta"
LOCATION"PR140"
$SEC"1"
CDS_SEC"1";
"A"
$PN"1"1;
"B"
$PN"2"41;
%"VCC15"
"1","(2075,3225)","0","logical_power","I15";
;
HDL_POWER"PVCCIN_CPU0_PVCC"
CDS_LIB"logical_power";
"A"1;
%"UNIVERSAL_GND"
"1","(2500,2675)","0","logical_power","I16";
;
CDS_LIB"logical_power"
HDL_POWER"GND";
"A"11;
%"Q_CAP"
"1","(2500,2900)","0","pure_quanta","I17";
;
PART_NUMBER"CH5222KEB01"
MATERIAL"X6S"
TOLERANCE"10%"
VALUE"2.2UF"
VOLTAGE"10V"
PACK_TYPE"C0402"
LOCATION"PC250_P0_6"
CDS_LIB"pure_quanta"
LOCATION"PC250_P0_6"
$SEC"1"
CDS_SEC"1";
"B"
$PN"2"11;
"A"
$PN"1"1;
%"Q_RES"
"2","(1675,1400)","2","pure_quanta","I2";
;
PART_NUMBER"CS28872FB01"
WATTAGE"1/16W"
MATERIAL"EMPTY"
TOLERANCE"1%"
VALUE"8.87K"
PACK_TYPE"0402LF"
LOCATION"PR138"
CDS_LIB"pure_quanta"
$SEC"1"
CDS_SEC"1";
"A"
$PN"1"46;
"B"
$PN"2"7;
%"UNIVERSAL_GND"
"1","(1600,4450)","0","logical_power","I20";
;
CDS_LIB"logical_power"
HDL_POWER"GND";
"A"12;
%"UNIVERSAL_GND"
"1","(2100,4975)","0","logical_power","I23";
;
CDS_LIB"logical_power"
HDL_POWER"GND";
"A"13;
%"Q_CAP"
"1","(2100,5225)","0","pure_quanta","I24";
;
PART_NUMBER"CH5222KEB01"
MATERIAL"X6S"
TOLERANCE"10%"
VALUE"2.2UF"
VOLTAGE"10V"
PACK_TYPE"C0402"
LOCATION"PC249"
CDS_LIB"pure_quanta"
LOCATION"PC249"
$SEC"1"
CDS_SEC"1";
"B"
$PN"2"13;
"A"
$PN"1"35;
%"Q_CAP"
"2","(2425,4525)","0","pure_quanta","I25";
;
PART_NUMBER"CH4104K1B00"
VOLTAGE"25V"
VALUE"0.1UF"
TOLERANCE"10%"
PACK_TYPE"0402"
MATERIAL"X7R"
LOCATION"PC1343"
CDS_LIB"pure_quanta"
$SEC"1"
CDS_SEC"1";
"A"
$PN"1"12;
"B"
$PN"2"36;
%"Q_RES"
"2","(2100,5725)","0","pure_quanta","I26";
;
PART_NUMBER"CS-2202FB01"
WATTAGE"1/16W"
MATERIAL"CHIP"
TOLERANCE"1%"
VALUE"2.2"
PACK_TYPE"0402LF"
LOCATION"PR141"
CDS_LIB"pure_quanta"
LOCATION"PR141"
$SEC"1"
CDS_SEC"1";
"A"
$PN"1"2;
"B"
$PN"2"35;
%"VCC15"
"1","(2100,6050)","0","logical_power","I27";
;
HDL_POWER"PVCCIN_CPU0_PVCC"
CDS_LIB"logical_power";
"A"2;
%"UNIVERSAL_GND"
"1","(2525,5500)","0","logical_power","I28";
;
CDS_LIB"logical_power"
HDL_POWER"GND";
"A"14;
%"Q_CAP"
"1","(2525,5725)","0","pure_quanta","I29";
;
PART_NUMBER"CH5222KEB01"
MATERIAL"X6S"
TOLERANCE"10%"
VALUE"2.2UF"
VOLTAGE"10V"
PACK_TYPE"C0402"
LOCATION"PC251_P0_5"
CDS_LIB"pure_quanta"
LOCATION"PC251_P0_5"
$SEC"1"
CDS_SEC"1";
"B"
$PN"2"14;
"A"
$PN"1"2;
%"UNIVERSAL_GND"
"1","(1575,1625)","0","logical_power","I3";
;
CDS_LIB"logical_power"
HDL_POWER"GND";
"A"8;
%"UNIVERSAL_GND"
"1","(4250,1175)","0","logical_power","I30";
;
CDS_LIB"logical_power"
HDL_POWER"GND";
"A"15;
%"Q_INDUCTOR4P_14"
"1","(6025,1775)","0","pure_quanta","I32";
;
PART_NUMBER"CV+15^0TZ04"
VALUE"150NH"
MATERIAL"IND"
PART_TYPE"SMLF"
LOCATION"PL9"
NEEDS_NO_SIZE"TRUE"
CDS_LIB"pure_quanta"
SEC_TYPE""
SEC"1";
"1"
$PN"1"33;
"4"
$PN"4"5;
"3"
$PN"3"28;
"2"
$PN"2"31;
%"Q_CAP"
"1","(5575,2175)","2","pure_quanta","I33";
;
PART_NUMBER"CH4106K1B01"
MATERIAL"X7R"
TOLERANCE"10%"
VALUE"100NF"
VOLTAGE"50V"
PACK_TYPE"C0402"
LOCATION"PC256"
CDS_LIB"pure_quanta"
$SEC"1"
CDS_SEC"1";
"B"
$PN"2"32;
"A"
$PN"1"29;
%"Q_CAP"
"1","(4400,2800)","0","pure_quanta","I34";
;
PART_NUMBER"TMP_QCH2336K1B12"
MATERIAL"X7R"
TOLERANCE"10%"
VALUE"3300PF"
VOLTAGE"50V"
PACK_TYPE"0402"
LOCATION"PC252_P0_6"
CDS_LIB"pure_quanta"
LOCATION"PC252_P0_6"
$SEC"1"
CDS_SEC"1";
"B"
$PN"2"17;
"A"
$PN"1"3;
%"Q_RES"
"1","(4850,2350)","0","pure_quanta","I35";
;
PART_NUMBER"CS-3302FB01"
WATTAGE"1/16W"
TOLERANCE"1%"
MATERIAL"CHIP"
VALUE"3.3"
PACK_TYPE"0402LF"
LOCATION"PR1770"
CDS_LIB"pure_quanta"
$SEC"1"
CDS_SEC"1";
"B"
$PN"2"29;
"A"
$PN"1"30;
%"UNIVERSAL_GND"
"1","(4275,4000)","0","logical_power","I36";
;
CDS_LIB"logical_power"
HDL_POWER"GND";
"A"16;
%"Q_CAP"
"1","(4800,2800)","0","pure_quanta","I37";
;
PART_NUMBER"CH5103KEB01"
MATERIAL"X6S"
TOLERANCE"10%"
VALUE"1UF"
VOLTAGE"16V"
PACK_TYPE"C0402"
LOCATION"PC254_P0_6"
CDS_LIB"pure_quanta"
LOCATION"PC254_P0_6"
$SEC"1"
CDS_SEC"1";
"B"
$PN"2"17;
"A"
$PN"1"3;
%"Q_CAP"
"1","(5200,2800)","0","pure_quanta","I38";
;
PART_NUMBER"CH6223MEA01"
MATERIAL"X6S"
TOLERANCE"20%"
VALUE"22UF"
VOLTAGE"16V"
PACK_TYPE"C0805"
LOCATION"PC258_P0_6"
CDS_LIB"pure_quanta"
LOCATION"PC258_P0_6"
$SEC"1"
CDS_SEC"1";
"B"
$PN"2"17;
"A"
$PN"1"3;
%"Q_CAP"
"1","(5600,2800)","0","pure_quanta","I39";
;
PART_NUMBER"CH6223MEA01"
MATERIAL"X6S"
TOLERANCE"20%"
VALUE"22UF"
VOLTAGE"16V"
PACK_TYPE"C0805"
LOCATION"PC260_P0_6"
CDS_LIB"pure_quanta"
LOCATION"PC260_P0_6"
$SEC"1"
CDS_SEC"1";
"B"
$PN"2"17;
"A"
$PN"1"3;
%"Q_RES"
"2","(1700,4225)","2","pure_quanta","I4";
;
PART_NUMBER"CS28872FB01"
WATTAGE"1/16W"
MATERIAL"EMPTY"
TOLERANCE"1%"
VALUE"8.87K"
PACK_TYPE"0402LF"
LOCATION"PR139"
CDS_LIB"pure_quanta"
$SEC"1"
CDS_SEC"1";
"A"
$PN"1"38;
"B"
$PN"2"9;
%"Q_RES"
"1","(6125,1375)","0","pure_quanta","I40";
;
PART_NUMBER"CS00002JB13"
WATTAGE"1/16W"
MATERIAL"CHIP"
TOLERANCE"5%"
VALUE"0"
PACK_TYPE"0402LF"
LOCATION"PR142"
CDS_LIB"pure_quanta"
$SEC"1"
CDS_SEC"1";
"B"
$PN"2"5;
"A"
$PN"1"34;
%"Q_CAP"
"1","(7725,1700)","0","pure_quanta","I42";
;
PART_NUMBER"CH622KMEA03"
PACK_TYPE"C0805"
VOLTAGE"4V"
VALUE"22UF"
TOLERANCE"20%"
MATERIAL"X6S"
LOCATION"PC266_P0_6"
CDS_LIB"pure_quanta"
LOCATION"PC266_P0_6"
$SEC"1"
CDS_SEC"1";
"B"
$PN"2"19;
"A"
$PN"1"5;
%"Q_CAP"
"1","(5975,2800)","0","pure_quanta","I43";
;
PART_NUMBER"CH6223MEA01"
MATERIAL"X6S"
TOLERANCE"20%"
VALUE"22UF"
VOLTAGE"16V"
PACK_TYPE"C0805"
LOCATION"PC262_P0_6"
CDS_LIB"pure_quanta"
LOCATION"PC262_P0_6"
$SEC"1"
CDS_SEC"1";
"B"
$PN"2"17;
"A"
$PN"1"3;
%"UNIVERSAL_GND"
"1","(6200,2375)","0","logical_power","I44";
;
CDS_LIB"logical_power"
HDL_POWER"GND";
"A"17;
%"VCC15"
"1","(6200,3175)","0","logical_power","I45";
;
HDL_POWER"SW_P12V_PVCCIN_CPU0_FLT"
CDS_LIB"logical_power";
"A"3;
%"Q_RES"
"1","(6150,4175)","0","pure_quanta","I46";
;
PART_NUMBER"CS00002JB13"
PACK_TYPE"0402LF"
VALUE"0"
MATERIAL"CHIP"
TOLERANCE"5%"
WATTAGE"1/16W"
LOCATION"PR143"
CDS_LIB"pure_quanta"
$SEC"1"
CDS_SEC"1";
"B"
$PN"2"6;
"A"
$PN"1"27;
%"Q_CAP"
"1","(4425,5625)","0","pure_quanta","I48";
;
PART_NUMBER"TMP_QCH2336K1B12"
MATERIAL"X7R"
TOLERANCE"10%"
VALUE"3300PF"
VOLTAGE"50V"
PACK_TYPE"0402"
LOCATION"PC253_P0_5"
CDS_LIB"pure_quanta"
LOCATION"PC253_P0_5"
$SEC"1"
CDS_SEC"1";
"B"
$PN"2"18;
"A"
$PN"1"4;
%"Q_RES"
"1","(4875,5175)","0","pure_quanta","I49";
;
PART_NUMBER"CS-3302FB01"
VALUE"3.3"
TOLERANCE"1%"
PACK_TYPE"0402LF"
MATERIAL"CHIP"
WATTAGE"1/16W"
LOCATION"PR1771"
CDS_LIB"pure_quanta"
$SEC"1"
CDS_SEC"1";
"B"
$PN"2"23;
"A"
$PN"1"26;
%"UNIVERSAL_GND"
"1","(1700,4000)","0","logical_power","I5";
;
CDS_LIB"logical_power"
HDL_POWER"GND";
"A"9;
%"Q_INDUCTOR4P_14"
"1","(6075,4600)","0","pure_quanta","I50";
;
PART_NUMBER"CV+15^0TZ04"
VALUE"150NH"
MATERIAL"IND"
PART_TYPE"SMLF"
LOCATION"PL10"
NEEDS_NO_SIZE"TRUE"
CDS_LIB"pure_quanta"
SEC_TYPE""
SEC"1";
"1"
$PN"1"24;
"4"
$PN"4"6;
"3"
$PN"3"21;
"2"
$PN"2"22;
%"Q_CAP"
"1","(5600,5000)","2","pure_quanta","I51";
;
PART_NUMBER"CH4106K1B01"
PACK_TYPE"C0402"
MATERIAL"X7R"
TOLERANCE"10%"
VALUE"100NF"
VOLTAGE"50V"
LOCATION"PC257"
CDS_LIB"pure_quanta"
$SEC"1"
CDS_SEC"1";
"B"
$PN"2"25;
"A"
$PN"1"23;
%"Q_CAP"
"1","(4825,5625)","0","pure_quanta","I52";
;
PART_NUMBER"CH5103KEB01"
MATERIAL"X6S"
TOLERANCE"10%"
VALUE"1UF"
VOLTAGE"16V"
PACK_TYPE"C0402"
LOCATION"PC255_P0_5"
CDS_LIB"pure_quanta"
LOCATION"PC255_P0_5"
$SEC"1"
CDS_SEC"1";
"B"
$PN"2"18;
"A"
$PN"1"4;
%"Q_CAP"
"1","(5225,5625)","0","pure_quanta","I53";
;
PART_NUMBER"CH6223MEA01"
MATERIAL"X6S"
TOLERANCE"20%"
VALUE"22UF"
VOLTAGE"16V"
PACK_TYPE"C0805"
LOCATION"PC259_P0_5"
CDS_LIB"pure_quanta"
LOCATION"PC259_P0_5"
$SEC"1"
CDS_SEC"1";
"B"
$PN"2"18;
"A"
$PN"1"4;
%"Q_CAP"
"1","(5625,5625)","0","pure_quanta","I54";
;
PART_NUMBER"CH6223MEA01"
MATERIAL"X6S"
TOLERANCE"20%"
VALUE"22UF"
VOLTAGE"16V"
PACK_TYPE"C0805"
LOCATION"PC261_P0_5"
CDS_LIB"pure_quanta"
LOCATION"PC261_P0_5"
$SEC"1"
CDS_SEC"1";
"B"
$PN"2"18;
"A"
$PN"1"4;
%"UNIVERSAL_GND"
"1","(6225,5200)","0","logical_power","I55";
;
CDS_LIB"logical_power"
HDL_POWER"GND";
"A"18;
%"Q_CAP"
"1","(6000,5625)","0","pure_quanta","I56";
;
PART_NUMBER"CH6223MEA01"
PACK_TYPE"C0805"
VOLTAGE"16V"
VALUE"22UF"
TOLERANCE"20%"
MATERIAL"X6S"
LOCATION"PC263_P0_5"
CDS_LIB"pure_quanta"
LOCATION"PC263_P0_5"
$SEC"1"
CDS_SEC"1";
"B"
$PN"2"18;
"A"
$PN"1"4;
%"VCC15"
"1","(6225,6000)","0","logical_power","I57";
;
HDL_POWER"SW_P12V_PVCCIN_CPU0_FLT"
CDS_LIB"logical_power";
"A"4;
%"Q_CAP"
"1","(8150,1700)","0","pure_quanta","I59";
;
PART_NUMBER"CH622KMEA03"
PACK_TYPE"C0805"
VOLTAGE"4V"
VALUE"22UF"
TOLERANCE"20%"
MATERIAL"X6S"
LOCATION"PC268_P0_6"
CDS_LIB"pure_quanta"
LOCATION"PC268_P0_6"
$SEC"1"
CDS_SEC"1";
"B"
$PN"2"19;
"A"
$PN"1"5;
%"UNIVERSAL_GND"
"1","(8450,1325)","0","logical_power","I60";
;
CDS_LIB"logical_power"
HDL_POWER"GND";
"A"19;
%"VCC15"
"1","(8450,2100)","0","logical_power","I61";
;
HDL_POWER"PVCCIN_CPU0"
CDS_LIB"logical_power";
"A"5;
%"UNIVERSAL_GND"
"1","(8650,4150)","0","logical_power","I62";
;
CDS_LIB"logical_power"
HDL_POWER"GND";
"A"20;
%"Q_CAP"
"1","(7925,4525)","0","pure_quanta","I63";
;
PART_NUMBER"CH622KMEA03"
PACK_TYPE"C0805"
VOLTAGE"4V"
VALUE"22UF"
TOLERANCE"20%"
MATERIAL"X6S"
LOCATION"PC267_P0_5"
CDS_LIB"pure_quanta"
LOCATION"PC267_P0_5"
$SEC"1"
CDS_SEC"1";
"B"
$PN"2"20;
"A"
$PN"1"6;
%"Q_CAP"
"1","(8350,4525)","0","pure_quanta","I64";
;
PART_NUMBER"CH622KMEA03"
PACK_TYPE"C0805"
VOLTAGE"4V"
VALUE"22UF"
TOLERANCE"20%"
MATERIAL"X6S"
LOCATION"PC269_P0_5"
CDS_LIB"pure_quanta"
LOCATION"PC269_P0_5"
$SEC"1"
CDS_SEC"1";
"B"
$PN"2"20;
"A"
$PN"1"6;
%"VCC15"
"1","(8650,4925)","0","logical_power","I65";
;
HDL_POWER"PVCCIN_CPU0"
CDS_LIB"logical_power";
"A"6;
%"ISL99390FRZTR5935"
"1","(3625,4725)","0","pure_quanta","I66";
;
PART_NUMBER"AL099390004"
PART_TYPE"SMLF"
MATERIAL"IC"
VALUE"ISL99390FRZ-TR5935"
LOCATION"PU9_P0_5"
NEEDS_NO_SIZE"TRUE"
CDS_LMAN_SYM_OUTLINE"-300,700,250,-650"
CDS_LIB"pure_quanta"
$SEC"1"
CDS_SEC"1";
"PGND2"
$PN"7_9-20_24"16;
"GL2"
$PN"41"0;
"GL1"
$PN"6"0;
"DNC"
$PN"31"0;
"EN"
$PN"35"35;
"PGND3"
$PN"40"16;
"VOS"
$PN"1"27;
"VIN2"
$PN"30"4;
"PGND1"
$PN"5"16;
"SW"
$PN"10_19"24;
"LSET"
$PN"37"38;
"IOUT"
$PN"38"37;
"TOUT_FLT"
$PN"36"40;
"PVCC"
$PN"4"2;
"PHASE"
$PN"32"25;
"VIN1"
$PN"25_29"4;
"BOOT"
$PN"33"26;
"AGND"
$PN"2"16;
"VCC"
$PN"3"35;
"REFIN"
$PN"39"36;
"PWM"
$PN"34"39;
END.
